# S9S_MB_2U (Grand Teton) — schematic netlist excerpt (pin names and nets, part order shuffled) for the footprints in the layout excerpt that follows; sources: Cadence DE-HDL packaged netlist, KiCad conversion of 03242023_DA0F0TMBIJ0_F0T_Motherboard_J_brd_V01_OCP.brd

R409  Q_RES  4.7K 1% EMPTY  pkg 0402LF  page 153 : A = P3V3_OCP_SFF ; B = OCP_SFF_ID0
R3887  Q_RES  49.9 1% CHIP  pkg 0402LF  page 94 : A = I3C_SPD_DDREFGH_CPU0_LVC1_SCL_4 ; B = I3C_SPD_DDREFGH_CPU0_LVC1_SCL

(kicad_pcb
	(version 20260206)
	(generator "pcbnew")
	(generator_version "10.0")
	(general
		(thickness 1.6)
		(legacy_teardrops no)
	)
	(paper "A4")
	(title_block
		(title "03242023_DA0F0TMBIJ0_F0T_Motherboard_J_brd_V01_OCP.brd")
		(comment 1 "Grand Teton / footprints 5323-5324 of 6105")
	)
	(layers
		(0 "F.Cu" signal "TOP")
		(4 "In1.Cu" signal "GND")
		(6 "In2.Cu" signal "IN1")
		(8 "In3.Cu" signal "GND1")
		(10 "In4.Cu" signal "IN2")
		(12 "In5.Cu" signal "GND2")
		(14 "In6.Cu" signal "IN3")
		(16 "In7.Cu" signal "GND3")
		(18 "In8.Cu" signal "VCC")
		(20 "In9.Cu" signal "VCC1")
		(22 "In10.Cu" signal "GND4")
		(24 "In11.Cu" signal "IN4")
		(26 "In12.Cu" signal "GND5")
		(28 "In13.Cu" signal "IN5")
		(30 "In14.Cu" signal "GND6")
		(32 "In15.Cu" signal "IN6")
		(34 "In16.Cu" signal "GND7")
		(2 "B.Cu" signal "BOTTOM")
		(9 "F.Adhes" user "F.Adhesive")
		(11 "B.Adhes" user "B.Adhesive")
		(13 "F.Paste" user "Package Geometry/Pastemask Top")
		(15 "B.Paste" user "Package Geometry/Pastemask Bottom")
		(5 "F.SilkS" user "Ref Des/Silkscreen Top")
		(7 "B.SilkS" user "Ref Des/Silkscreen Bottom")
		(1 "F.Mask" user "Board Geometry/Soldermask Top")
		(3 "B.Mask" user "Board Geometry/Soldermask Bottom")
		(17 "Dwgs.User" user "User.Drawings")
		(19 "Cmts.User" user "User.Comments")
		(21 "Eco1.User" user "User.Eco1")
		(23 "Eco2.User" user "User.Eco2")
		(25 "Edge.Cuts" user "Board Geometry/Outline")
		(27 "Margin" user)
		(31 "F.CrtYd" user "Package Geometry/Place Bound Top")
		(29 "B.CrtYd" user "Package Geometry/Place Bound Bottom")
		(35 "F.Fab" user "Ref Des/Assembly Top")
		(33 "B.Fab" user "Ref Des/Assembly Bottom")
	)
	(footprint ""
		(layer "B.Cu")
		(at 446.55105 -10.594086 -90)
		(property "Reference" "R409"
			(at 0 0 90)
			(layer "B.SilkS")
			(hide yes)
			(effects
				(font
					(size 1.27 1.27)
				)
				(justify mirror)
			)
		)
		(property "Value" ""
			(at 0 0 90)
			(layer "B.Fab")
			(effects
				(font
					(size 1.27 1.27)
				)
				(justify mirror)
			)
		)
		(duplicate_pad_numbers_are_jumpers no)
		(fp_line
			(start -0.7874 0.4064)
			(end 0.7874 0.4064)
			(stroke
				(width 0.1524)
				(type default)
			)
			(layer "B.SilkS")
		)
		(fp_line
			(start 0.7874 0.4064)
			(end 0.7874 -0.4064)
			(stroke
				(width 0.1524)
				(type default)
			)
			(layer "B.SilkS")
		)
		(fp_line
			(start -0.7874 -0.4064)
			(end -0.7874 0.4064)
			(stroke
				(width 0.1524)
				(type default)
			)
			(layer "B.SilkS")
		)
		(fp_line
			(start 0.7874 -0.4064)
			(end -0.7874 -0.4064)
			(stroke
				(width 0.1524)
				(type default)
			)
			(layer "B.SilkS")
		)
		(fp_line
			(start -0.67945 0.3048)
			(end -0.120396 0.3048)
			(stroke
				(width 0.1)
				(type default)
			)
			(layer "B.Fab")
		)
		(fp_line
			(start -0.120396 0.3048)
			(end -0.120396 0.2794)
			(stroke
				(width 0.1)
				(type default)
			)
			(layer "B.Fab")
		)
		(fp_line
			(start 0.12065 0.3048)
			(end 0.67945 0.3048)
			(stroke
				(width 0.1)
				(type default)
			)
			(layer "B.Fab")
		)
		(fp_line
			(start 0.67945 0.3048)
			(end 0.67945 -0.305054)
			(stroke
				(width 0.1)
				(type default)
			)
			(layer "B.Fab")
		)
		(fp_line
			(start -0.120396 0.2794)
			(end 0.12065 0.2794)
			(stroke
				(width 0.1)
				(type default)
			)
			(layer "B.Fab")
		)
		(fp_line
			(start 0.12065 0.2794)
			(end 0.12065 0.3048)
			(stroke
				(width 0.1)
				(type default)
			)
			(layer "B.Fab")
		)
		(fp_line
			(start -0.12065 -0.2794)
			(end -0.12065 -0.3048)
			(stroke
				(width 0.1)
				(type default)
			)
			(layer "B.Fab")
		)
		(fp_line
			(start 0.12065 -0.2794)
			(end -0.12065 -0.2794)
			(stroke
				(width 0.1)
				(type default)
			)
			(layer "B.Fab")
		)
		(fp_line
			(start -0.67945 -0.3048)
			(end -0.67945 0.3048)
			(stroke
				(width 0.1)
				(type default)
			)
			(layer "B.Fab")
		)
		(fp_line
			(start -0.12065 -0.3048)
			(end -0.67945 -0.3048)
			(stroke
				(width 0.1)
				(type default)
			)
			(layer "B.Fab")
		)
		(fp_line
			(start 0.12065 -0.305054)
			(end 0.12065 -0.2794)
			(stroke
				(width 0.1)
				(type default)
			)
			(layer "B.Fab")
		)
		(fp_line
			(start 0.67945 -0.305054)
			(end 0.12065 -0.305054)
			(stroke
				(width 0.1)
				(type default)
			)
			(layer "B.Fab")
		)
		(pad "1" smd circle
			(at 0.40005 0 90)
			(size 0 0)
			(layers "B.Cu" "B.Mask" "B.Paste")
			(net "P3V3_OCP_SFF")
		)
		(pad "2" smd circle
			(at -0.40005 0 90)
			(size 0 0)
			(layers "B.Cu" "B.Mask" "B.Paste")
			(net "OCP_SFF_ID0")
		)
	)
	(footprint ""
		(layer "B.Cu")
		(at 444.42126 -316.709044 90)
		(property "Reference" "R3887"
			(at 0 0 90)
			(layer "B.SilkS")
			(hide yes)
			(effects
				(font
					(size 1.27 1.27)
				)
				(justify mirror)
			)
		)
		(property "Value" ""
			(at 0 0 90)
			(layer "B.Fab")
			(effects
				(font
					(size 1.27 1.27)
				)
				(justify mirror)
			)
		)
		(duplicate_pad_numbers_are_jumpers no)
		(fp_line
			(start 0.7874 -0.4064)
			(end -0.7874 -0.4064)
			(stroke
				(width 0.1524)
				(type default)
			)
			(layer "B.SilkS")
		)
		(fp_line
			(start -0.7874 -0.4064)
			(end -0.7874 0.4064)
			(stroke
				(width 0.1524)
				(type default)
			)
			(layer "B.SilkS")
		)
		(fp_line
			(start 0.7874 0.4064)
			(end 0.7874 -0.4064)
			(stroke
				(width 0.1524)
				(type default)
			)
			(layer "B.SilkS")
		)
		(fp_line
			(start -0.7874 0.4064)
			(end 0.7874 0.4064)
			(stroke
				(width 0.1524)
				(type default)
			)
			(layer "B.SilkS")
		)
		(fp_line
			(start 0.67945 -0.305054)
			(end 0.12065 -0.305054)
			(stroke
				(width 0.1)
				(type default)
			)
			(layer "B.Fab")
		)
		(fp_line
			(start 0.12065 -0.305054)
			(end 0.12065 -0.2794)
			(stroke
				(width 0.1)
				(type default)
			)
			(layer "B.Fab")
		)
		(fp_line
			(start -0.12065 -0.3048)
			(end -0.67945 -0.3048)
			(stroke
				(width 0.1)
				(type default)
			)
			(layer "B.Fab")
		)
		(fp_line
			(start -0.67945 -0.3048)
			(end -0.67945 0.3048)
			(stroke
				(width 0.1)
				(type default)
			)
			(layer "B.Fab")
		)
		(fp_line
			(start 0.12065 -0.2794)
			(end -0.12065 -0.2794)
			(stroke
				(width 0.1)
				(type default)
			)
			(layer "B.Fab")
		)
		(fp_line
			(start -0.12065 -0.2794)
			(end -0.12065 -0.3048)
			(stroke
				(width 0.1)
				(type default)
			)
			(layer "B.Fab")
		)
		(fp_line
			(start 0.12065 0.2794)
			(end 0.12065 0.3048)
			(stroke
				(width 0.1)
				(type default)
			)
			(layer "B.Fab")
		)
		(fp_line
			(start -0.120396 0.2794)
			(end 0.12065 0.2794)
			(stroke
				(width 0.1)
				(type default)
			)
			(layer "B.Fab")
		)
		(fp_line
			(start 0.67945 0.3048)
			(end 0.67945 -0.305054)
			(stroke
				(width 0.1)
				(type default)
			)
			(layer "B.Fab")
		)
		(fp_line
			(start 0.12065 0.3048)
			(end 0.67945 0.3048)
			(stroke
				(width 0.1)
				(type default)
			)
			(layer "B.Fab")
		)
		(fp_line
			(start -0.120396 0.3048)
			(end -0.120396 0.2794)
			(stroke
				(width 0.1)
				(type default)
			)
			(layer "B.Fab")
		)
		(fp_line
			(start -0.67945 0.3048)
			(end -0.120396 0.3048)
			(stroke
				(width 0.1)
				(type default)
			)
			(layer "B.Fab")
		)
		(pad "1" smd circle
			(at 0.40005 0 270)
			(size 0 0)
			(layers "B.Cu" "B.Mask" "B.Paste")
			(net "I3C_SPD_DDREFGH_CPU0_LVC1_SCL_4")
		)
		(pad "2" smd circle
			(at -0.40005 0 270)
			(size 0 0)
			(layers "B.Cu" "B.Mask" "B.Paste")
			(net "I3C_SPD_DDREFGH_CPU0_LVC1_SCL")
		)
	)
)
